(kicad_pcb
	(version 20260206)
	(generator "pcbnew")
	(generator_version "10.0")
	(general
		(thickness 1.6)
		(legacy_teardrops no)
	)
	(paper "A4")
	(title_block
		(title "v1-chassis-manager — T6M_CM_d_v01_1031_1645.brd")
		(comment 1 "Open CloudServer (Microsoft) / footprints 1499-1506 of 2512")
	)
	(layers
		(0 "F.Cu" signal "TOP")
		(4 "In1.Cu" signal "GND1")
		(6 "In2.Cu" signal "IN1")
		(8 "In3.Cu" signal "VCC1")
		(10 "In4.Cu" signal "VCC2")
		(12 "In5.Cu" signal "GND2")
		(14 "In6.Cu" signal "IN2")
		(16 "In7.Cu" signal "IN3")
		(18 "In8.Cu" signal "GND3")
		(2 "B.Cu" signal "BOTTOM")
		(9 "F.Adhes" user "F.Adhesive")
		(11 "B.Adhes" user "B.Adhesive")
		(13 "F.Paste" user "Package Geometry/Pastemask Top")
		(15 "B.Paste" user "Package Geometry/Pastemask Bottom")
		(5 "F.SilkS" user "Ref Des/Silkscreen Top")
		(7 "B.SilkS" user "Ref Des/Silkscreen Bottom")
		(1 "F.Mask" user "Board Geometry/Soldermask Top")
		(3 "B.Mask" user "Board Geometry/Soldermask Bottom")
		(17 "Dwgs.User" user "User.Drawings")
		(19 "Cmts.User" user "User.Comments")
		(21 "Eco1.User" user "User.Eco1")
		(23 "Eco2.User" user "User.Eco2")
		(25 "Edge.Cuts" user "Board Geometry/Outline")
		(27 "Margin" user)
		(31 "F.CrtYd" user "Package Geometry/Place Bound Top")
		(29 "B.CrtYd" user "Package Geometry/Place Bound Bottom")
		(35 "F.Fab" user "Ref Des/Assembly Top")
		(33 "B.Fab" user "Ref Des/Assembly Bottom")
	)
	(footprint ""
		(layer "F.Cu")
		(at 48.262794 -4.40309 90)
		(property "Reference" "PC72"
			(at -3.823462 -15.310612 90)
			(unlocked yes)
			(layer "F.SilkS")
			(effects
				(font
					(size 0.7874 0.5842)
					(thickness 0.1524)
				)
				(justify left)
			)
		)
		(property "Value" ""
			(at 0 0 90)
			(layer "F.Fab")
			(effects
				(font
					(size 1.27 1.27)
				)
			)
		)
		(duplicate_pad_numbers_are_jumpers no)
		(fp_line
			(start 2.2098 -0.9398)
			(end 2.2098 0.9398)
			(stroke
				(width 0.1524)
				(type default)
			)
			(layer "F.SilkS")
		)
		(fp_line
			(start 0 -0.9398)
			(end 0 0.9398)
			(stroke
				(width 0.1524)
				(type default)
			)
			(layer "F.SilkS")
		)
		(fp_line
			(start -2.2098 -0.9398)
			(end 2.2098 -0.9398)
			(stroke
				(width 0.1524)
				(type default)
			)
			(layer "F.SilkS")
		)
		(fp_line
			(start 2.2098 0.9398)
			(end -2.2098 0.9398)
			(stroke
				(width 0.1524)
				(type default)
			)
			(layer "F.SilkS")
		)
		(fp_line
			(start -2.2098 0.9398)
			(end -2.2098 -0.9398)
			(stroke
				(width 0.1524)
				(type default)
			)
			(layer "F.SilkS")
		)
		(fp_poly
			(pts
				(xy -1.6764 0.889) (xy -1.6764 0.7874) (xy -2.0574 0.7874) (xy -2.0574 -0.7874) (xy -1.6764 -0.7874)
				(xy -1.6764 -0.9398) (xy 1.6764 -0.9398) (xy 1.6764 -0.7874) (xy 2.0574 -0.7874) (xy 2.0574 0.7874)
				(xy 1.6764 0.7874) (xy 1.6764 0.9398) (xy -1.6764 0.9398)
			)
			(stroke
				(width 0)
				(type default)
			)
			(fill no)
			(layer "F.CrtYd")
		)
		(fp_line
			(start 1.700022 -0.899922)
			(end 1.700022 0.899922)
			(stroke
				(width 0.1)
				(type default)
			)
			(layer "F.Fab")
		)
		(fp_line
			(start -1.700022 -0.899922)
			(end 1.700022 -0.899922)
			(stroke
				(width 0.1)
				(type default)
			)
			(layer "F.Fab")
		)
		(fp_line
			(start 1.700022 0.899922)
			(end -1.700022 0.899922)
			(stroke
				(width 0.1)
				(type default)
			)
			(layer "F.Fab")
		)
		(fp_line
			(start -1.700022 0.899922)
			(end -1.700022 -0.899922)
			(stroke
				(width 0.1)
				(type default)
			)
			(layer "F.Fab")
		)
		(pad "1" smd rect
			(at 1.4732 0 90)
			(size 1.1684 1.5748)
			(layers "F.Cu" "F.Mask" "F.Paste")
			(net "SW_PV_VDDR_NODE1_VIN_FLT")
		)
		(pad "2" smd rect
			(at -1.4732 0 90)
			(size 1.1684 1.5748)
			(layers "F.Cu" "F.Mask" "F.Paste")
			(net "GND")
		)
	)
	(footprint ""
		(layer "F.Cu")
		(at 42.328084 -123.472702 90)
		(property "Reference" "R259"
			(at -1.245362 -1.558798 90)
			(unlocked yes)
			(layer "F.SilkS")
			(effects
				(font
					(size 0.7874 0.5842)
					(thickness 0.1524)
				)
				(justify left)
			)
		)
		(property "Value" ""
			(at 0 0 90)
			(layer "F.Fab")
			(effects
				(font
					(size 1.27 1.27)
				)
			)
		)
		(duplicate_pad_numbers_are_jumpers no)
		(fp_line
			(start 0.7874 -0.4064)
			(end 0.7874 0.4064)
			(stroke
				(width 0.1524)
				(type default)
			)
			(layer "F.SilkS")
		)
		(fp_line
			(start -0.7874 -0.4064)
			(end 0.7874 -0.4064)
			(stroke
				(width 0.1524)
				(type default)
			)
			(layer "F.SilkS")
		)
		(fp_line
			(start 0.7874 0.4064)
			(end -0.7874 0.4064)
			(stroke
				(width 0.1524)
				(type default)
			)
			(layer "F.SilkS")
		)
		(fp_line
			(start -0.7874 0.4064)
			(end -0.7874 -0.4064)
			(stroke
				(width 0.1524)
				(type default)
			)
			(layer "F.SilkS")
		)
		(fp_poly
			(pts
				(xy -0.508 0.2794) (xy -0.508 0.2286) (xy -0.635 0.2286) (xy -0.635 -0.254) (xy -0.5334 -0.254)
				(xy -0.5334 -0.2794) (xy 0.5334 -0.2794) (xy 0.5334 -0.254) (xy 0.635 -0.254) (xy 0.635 0.254) (xy 0.5334 0.254)
				(xy 0.5334 0.2794)
			)
			(stroke
				(width 0)
				(type default)
			)
			(fill no)
			(layer "F.CrtYd")
		)
		(pad "1" smd rect
			(at 0.40005 0 90)
			(size 0.4572 0.508)
			(layers "F.Cu" "F.Mask" "F.Paste")
			(net "BMC_NODE1_DDR_RST_L")
		)
		(pad "2" smd rect
			(at -0.40005 0 90)
			(size 0.4572 0.508)
			(layers "F.Cu" "F.Mask" "F.Paste")
			(net "P1V538_BMC_NODE1")
		)
	)
	(footprint ""
		(layer "F.Cu")
		(at 58.40476 -178.804824 180)
		(property "Reference" "U95"
			(at 8.534908 -132.653786 90)
			(unlocked yes)
			(layer "F.SilkS")
			(effects
				(font
					(size 0.7874 0.5842)
					(thickness 0.1524)
				)
			)
		)
		(property "Value" ""
			(at 0 0 180)
			(layer "F.Fab")
			(effects
				(font
					(size 1.27 1.27)
				)
			)
		)
		(duplicate_pad_numbers_are_jumpers no)
		(fp_line
			(start 1.651 1.905)
			(end -1.651 1.905)
			(stroke
				(width 0.1524)
				(type default)
			)
			(layer "F.SilkS")
		)
		(fp_line
			(start 1.651 -1.905)
			(end 1.651 1.905)
			(stroke
				(width 0.1524)
				(type default)
			)
			(layer "F.SilkS")
		)
		(fp_line
			(start -1.651 1.905)
			(end -1.651 -1.905)
			(stroke
				(width 0.1524)
				(type default)
			)
			(layer "F.SilkS")
		)
		(fp_line
			(start -1.651 -1.905)
			(end 1.651 -1.905)
			(stroke
				(width 0.1524)
				(type default)
			)
			(layer "F.SilkS")
		)
		(fp_poly
			(pts
				(xy -1.524 0.7112) (xy -1.524 1.7526) (xy -0.508 1.7526) (xy -0.508 0.6985) (xy 0.508 0.6985) (xy 0.508 1.7526)
				(xy 1.524 1.7526) (xy 1.524 0.6985) (xy 1.524 -0.6985) (xy 0.508 -0.6985) (xy 0.508 -1.7526) (xy -0.508 -1.7526)
				(xy -0.508 -0.6985) (xy -1.524 -0.6985) (xy -1.524 0.6985)
			)
			(stroke
				(width 0)
				(type default)
			)
			(fill no)
			(layer "F.CrtYd")
		)
		(fp_text user "S"
			(at 1.143508 2.741168 0)
			(unlocked yes)
			(layer "F.SilkS")
			(effects
				(font
					(size 0.635 0.4064)
					(thickness 0.1524)
				)
			)
		)
		(fp_text user "D"
			(at -0.114046 -2.4511 0)
			(unlocked yes)
			(layer "F.SilkS")
			(effects
				(font
					(size 0.635 0.4064)
					(thickness 0.1524)
				)
			)
		)
		(fp_text user "G"
			(at -1.396492 2.487168 0)
			(unlocked yes)
			(layer "F.SilkS")
			(effects
				(font
					(size 0.635 0.4064)
					(thickness 0.1524)
				)
			)
		)
		(pad "D" smd rect
			(at 0 -1.1176 180)
			(size 1.016 1.27)
			(layers "F.Cu" "F.Mask" "F.Paste")
			(net "PSU_DC_OK_N")
		)
		(pad "G" smd rect
			(at -1.016 1.1176 180)
			(size 1.016 1.27)
			(layers "F.Cu" "F.Mask" "F.Paste")
			(net "PSU3_DC_OK_R_BUF")
		)
		(pad "S" smd rect
			(at 1.016 1.1176 180)
			(size 1.016 1.27)
			(layers "F.Cu" "F.Mask" "F.Paste")
			(net "GND")
		)
	)
	(footprint ""
		(layer "F.Cu")
		(at 91.803982 -137.581894 90)
		(property "Reference" "R1084"
			(at 1.288542 -0.084328 90)
			(unlocked yes)
			(layer "F.SilkS")
			(effects
				(font
					(size 0.7874 0.5842)
					(thickness 0.1524)
				)
				(justify left)
			)
		)
		(property "Value" ""
			(at 0 0 90)
			(layer "F.Fab")
			(effects
				(font
					(size 1.27 1.27)
				)
			)
		)
		(duplicate_pad_numbers_are_jumpers no)
		(fp_line
			(start 0.7874 -0.4064)
			(end 0.7874 0.4064)
			(stroke
				(width 0.1524)
				(type default)
			)
			(layer "F.SilkS")
		)
		(fp_line
			(start -0.7874 -0.4064)
			(end 0.7874 -0.4064)
			(stroke
				(width 0.1524)
				(type default)
			)
			(layer "F.SilkS")
		)
		(fp_line
			(start 0.7874 0.4064)
			(end -0.7874 0.4064)
			(stroke
				(width 0.1524)
				(type default)
			)
			(layer "F.SilkS")
		)
		(fp_line
			(start -0.7874 0.4064)
			(end -0.7874 -0.4064)
			(stroke
				(width 0.1524)
				(type default)
			)
			(layer "F.SilkS")
		)
		(fp_poly
			(pts
				(xy -0.508 0.2794) (xy -0.508 0.2286) (xy -0.635 0.2286) (xy -0.635 -0.254) (xy -0.5334 -0.254)
				(xy -0.5334 -0.2794) (xy 0.5334 -0.2794) (xy 0.5334 -0.254) (xy 0.635 -0.254) (xy 0.635 0.254) (xy 0.5334 0.254)
				(xy 0.5334 0.2794)
			)
			(stroke
				(width 0)
				(type default)
			)
			(fill no)
			(layer "F.CrtYd")
		)
		(pad "1" smd rect
			(at 0.40005 0 90)
			(size 0.4572 0.508)
			(layers "F.Cu" "F.Mask" "F.Paste")
			(net "P3V3_STB_NODE1")
		)
		(pad "2" smd rect
			(at -0.40005 0 90)
			(size 0.4572 0.508)
			(layers "F.Cu" "F.Mask" "F.Paste")
			(net "PWRGD_NODE1_P1V05_SUS_PG")
		)
	)
	(footprint ""
		(layer "F.Cu")
		(at 123.701302 -54.466236 -90)
		(property "Reference" "U103"
			(at 2.357628 1.498854 0)
			(unlocked yes)
			(layer "F.SilkS")
			(effects
				(font
					(size 0.7874 0.5842)
					(thickness 0.1524)
				)
			)
		)
		(property "Value" ""
			(at 0 0 270)
			(layer "F.Fab")
			(effects
				(font
					(size 1.27 1.27)
				)
			)
		)
		(duplicate_pad_numbers_are_jumpers no)
		(fp_line
			(start -1.651 1.905)
			(end -1.651 -1.905)
			(stroke
				(width 0.1524)
				(type default)
			)
			(layer "F.SilkS")
		)
		(fp_line
			(start 1.651 1.905)
			(end -1.651 1.905)
			(stroke
				(width 0.1524)
				(type default)
			)
			(layer "F.SilkS")
		)
		(fp_line
			(start -1.651 -1.905)
			(end 1.651 -1.905)
			(stroke
				(width 0.1524)
				(type default)
			)
			(layer "F.SilkS")
		)
		(fp_line
			(start 1.651 -1.905)
			(end 1.651 1.905)
			(stroke
				(width 0.1524)
				(type default)
			)
			(layer "F.SilkS")
		)
		(fp_poly
			(pts
				(xy -1.524 0.7112) (xy -1.524 1.7526) (xy -0.508 1.7526) (xy -0.508 0.6985) (xy 0.508 0.6985) (xy 0.508 1.7526)
				(xy 1.524 1.7526) (xy 1.524 0.6985) (xy 1.524 -0.6985) (xy 0.508 -0.6985) (xy 0.508 -1.7526) (xy -0.508 -1.7526)
				(xy -0.508 -0.6985) (xy -1.524 -0.6985) (xy -1.524 0.6985)
			)
			(stroke
				(width 0)
				(type default)
			)
			(fill no)
			(layer "F.CrtYd")
		)
		(fp_text user "G"
			(at -1.165098 2.259076 0)
			(unlocked yes)
			(layer "F.SilkS")
			(effects
				(font
					(size 0.635 0.4064)
					(thickness 0.1524)
				)
			)
		)
		(fp_text user "S"
			(at 2.54254 -0.824738 0)
			(unlocked yes)
			(layer "F.SilkS")
			(effects
				(font
					(size 0.635 0.4064)
					(thickness 0.1524)
				)
			)
		)
		(fp_text user "D"
			(at 2.25552 -1.786128 0)
			(unlocked yes)
			(layer "F.SilkS")
			(effects
				(font
					(size 0.635 0.4064)
					(thickness 0.1524)
				)
			)
		)
		(pad "D" smd rect
			(at 0 -1.1176 270)
			(size 1.016 1.27)
			(layers "F.Cu" "F.Mask" "F.Paste")
			(net "COM4_EN_N")
		)
		(pad "G" smd rect
			(at -1.016 1.1176 270)
			(size 1.016 1.27)
			(layers "F.Cu" "F.Mask" "F.Paste")
			(net "CPLD_UART_RI_P3_N")
		)
		(pad "S" smd rect
			(at 1.016 1.1176 270)
			(size 1.016 1.27)
			(layers "F.Cu" "F.Mask" "F.Paste")
			(net "GND")
		)
	)
	(footprint ""
		(layer "F.Cu")
		(at 154.551126 -166.515288 180)
		(property "Reference" "R579"
			(at 5.148834 4.392676 0)
			(unlocked yes)
			(layer "F.SilkS")
			(effects
				(font
					(size 0.7874 0.5842)
					(thickness 0.1524)
				)
				(justify left)
			)
		)
		(property "Value" ""
			(at 0 0 180)
			(layer "F.Fab")
			(effects
				(font
					(size 1.27 1.27)
				)
			)
		)
		(duplicate_pad_numbers_are_jumpers no)
		(fp_line
			(start 0.7874 0.4064)
			(end -0.7874 0.4064)
			(stroke
				(width 0.1524)
				(type default)
			)
			(layer "F.SilkS")
		)
		(fp_line
			(start 0.7874 -0.4064)
			(end 0.7874 0.4064)
			(stroke
				(width 0.1524)
				(type default)
			)
			(layer "F.SilkS")
		)
		(fp_line
			(start -0.7874 0.4064)
			(end -0.7874 -0.4064)
			(stroke
				(width 0.1524)
				(type default)
			)
			(layer "F.SilkS")
		)
		(fp_line
			(start -0.7874 -0.4064)
			(end 0.7874 -0.4064)
			(stroke
				(width 0.1524)
				(type default)
			)
			(layer "F.SilkS")
		)
		(fp_poly
			(pts
				(xy -0.508 0.2794) (xy -0.508 0.2286) (xy -0.635 0.2286) (xy -0.635 -0.254) (xy -0.5334 -0.254)
				(xy -0.5334 -0.2794) (xy 0.5334 -0.2794) (xy 0.5334 -0.254) (xy 0.635 -0.254) (xy 0.635 0.254) (xy 0.5334 0.254)
				(xy 0.5334 0.2794)
			)
			(stroke
				(width 0)
				(type default)
			)
			(fill no)
			(layer "F.CrtYd")
		)
		(pad "1" smd rect
			(at 0.40005 0 180)
			(size 0.4572 0.508)
			(layers "F.Cu" "F.Mask" "F.Paste")
			(net "SPI_LAN2_NVM_SO")
		)
		(pad "2" smd rect
			(at -0.40005 0 180)
			(size 0.4572 0.508)
			(layers "F.Cu" "F.Mask" "F.Paste")
			(net "LAN2_NVM_SO_R")
		)
	)
	(footprint ""
		(layer "F.Cu")
		(at 58.606182 -173.527466 180)
		(property "Reference" "U86"
			(at 8.322818 -133.039612 90)
			(unlocked yes)
			(layer "F.SilkS")
			(effects
				(font
					(size 0.7874 0.5842)
					(thickness 0.1524)
				)
				(justify left)
			)
		)
		(property "Value" ""
			(at 0 0 180)
			(layer "F.Fab")
			(effects
				(font
					(size 1.27 1.27)
				)
			)
		)
		(duplicate_pad_numbers_are_jumpers no)
		(fp_line
			(start 1.549908 2.032)
			(end -1.549908 2.032)
			(stroke
				(width 0.1524)
				(type default)
			)
			(layer "F.SilkS")
		)
		(fp_line
			(start 1.549908 -2.032)
			(end 1.549908 2.032)
			(stroke
				(width 0.1524)
				(type default)
			)
			(layer "F.SilkS")
		)
		(fp_line
			(start -1.549908 2.032)
			(end -1.549908 -2.032)
			(stroke
				(width 0.1524)
				(type default)
			)
			(layer "F.SilkS")
		)
		(fp_line
			(start -1.549908 -2.032)
			(end 1.549908 -2.032)
			(stroke
				(width 0.1524)
				(type default)
			)
			(layer "F.SilkS")
		)
		(fp_poly
			(pts
				(xy -2.9464 1.016) (xy -2.9464 1.524) (xy -2.1844 1.27)
			)
			(stroke
				(width 0)
				(type default)
			)
			(fill yes)
			(layer "F.SilkS")
		)
		(fp_poly
			(pts
				(xy -1.549908 0.849884) (xy -1.2319 0.849884) (xy -1.2319 1.9431) (xy -1.1811 1.9431) (xy 1.1811 1.9431)
				(xy 1.2319 1.9431) (xy 1.2319 0.849884) (xy 1.549908 0.849884) (xy 1.549908 -0.849884) (xy 1.2319 -0.849884)
				(xy 1.2319 -1.9431) (xy 1.1811 -1.9431) (xy -1.1811 -1.9431) (xy -1.2319 -1.9431) (xy -1.2319 -0.849884)
				(xy -1.549908 -0.849884)
			)
			(stroke
				(width 0)
				(type default)
			)
			(fill no)
			(layer "F.CrtYd")
		)
		(fp_line
			(start 1.549908 0.849884)
			(end 1.549908 -0.849884)
			(stroke
				(width 0.1)
				(type default)
			)
			(layer "F.Fab")
		)
		(fp_line
			(start 1.549908 -0.849884)
			(end -1.549908 -0.849884)
			(stroke
				(width 0.1)
				(type default)
			)
			(layer "F.Fab")
		)
		(fp_line
			(start -1.549908 0.849884)
			(end 1.549908 0.849884)
			(stroke
				(width 0.1)
				(type default)
			)
			(layer "F.Fab")
		)
		(fp_line
			(start -1.549908 -0.849884)
			(end -1.549908 0.849884)
			(stroke
				(width 0.1)
				(type default)
			)
			(layer "F.Fab")
		)
		(fp_text user "3"
			(at 1.32207 2.510536 0)
			(unlocked yes)
			(layer "F.SilkS")
			(effects
				(font
					(size 0.635 0.4064)
					(thickness 0.1524)
				)
				(justify left)
			)
		)
		(fp_text user "4"
			(at 0.805942 -2.54508 0)
			(unlocked yes)
			(layer "F.SilkS")
			(effects
				(font
					(size 0.635 0.4064)
					(thickness 0.1524)
				)
				(justify left)
			)
		)
		(fp_text user "1"
			(at -1.165606 2.52222 0)
			(unlocked yes)
			(layer "F.SilkS")
			(effects
				(font
					(size 0.635 0.4064)
					(thickness 0.1524)
				)
				(justify left)
			)
		)
		(fp_text user "5"
			(at -1.838198 -2.59334 0)
			(unlocked yes)
			(layer "F.SilkS")
			(effects
				(font
					(size 0.635 0.4064)
					(thickness 0.1524)
				)
				(justify left)
			)
		)
		(pad "1" smd rect
			(at -0.94996 1.225042 180)
			(size 0.4572 1.3208)
			(layers "F.Cu" "F.Mask" "F.Paste")
			(net "Net_1707")
		)
		(pad "2" smd rect
			(at 0 1.225042 180)
			(size 0.4572 1.3208)
			(layers "F.Cu" "F.Mask" "F.Paste")
			(net "PSU3_DC_OK_R_BUF")
		)
		(pad "3" smd rect
			(at 0.94996 1.225042 180)
			(size 0.4572 1.3208)
			(layers "F.Cu" "F.Mask" "F.Paste")
			(net "GND")
		)
		(pad "4" smd rect
			(at 0.94996 -1.225042 180)
			(size 0.4572 1.3208)
			(layers "F.Cu" "F.Mask" "F.Paste")
			(net "PSU3_DC_OK")
		)
		(pad "5" smd rect
			(at -0.94996 -1.225042 180)
			(size 0.4572 1.3208)
			(layers "F.Cu" "F.Mask" "F.Paste")
			(net "P3V3_NODE1")
		)
	)
	(footprint ""
		(layer "F.Cu")
		(at 108.901738 -115.720368 180)
		(property "Reference" "PL8"
			(at -4.115054 -0.351028 90)
			(unlocked yes)
			(layer "F.SilkS")
			(effects
				(font
					(size 0.7874 0.5842)
					(thickness 0.1524)
				)
				(justify left)
			)
		)
		(property "Value" ""
			(at 0 0 180)
			(layer "F.Fab")
			(effects
				(font
					(size 1.27 1.27)
				)
			)
		)
		(duplicate_pad_numbers_are_jumpers no)
		(fp_line
			(start 3.359912 6.390132)
			(end 1.8542 6.390132)
			(stroke
				(width 0.1524)
				(type default)
			)
			(layer "F.SilkS")
		)
		(fp_line
			(start 3.359912 -0.849884)
			(end 3.359912 6.390132)
			(stroke
				(width 0.1524)
				(type default)
			)
			(layer "F.SilkS")
		)
		(fp_line
			(start 1.8542 -0.849884)
			(end 3.359912 -0.849884)
			(stroke
				(width 0.1524)
				(type default)
			)
			(layer "F.SilkS")
		)
		(fp_line
			(start -1.8542 6.390132)
			(end -3.359912 6.390132)
			(stroke
				(width 0.1524)
				(type default)
			)
			(layer "F.SilkS")
		)
		(fp_line
			(start -3.359912 6.390132)
			(end -3.359912 -0.849884)
			(stroke
				(width 0.1524)
				(type default)
			)
			(layer "F.SilkS")
		)
		(fp_line
			(start -3.359912 -0.849884)
			(end -1.8542 -0.849884)
			(stroke
				(width 0.1524)
				(type default)
			)
			(layer "F.SilkS")
		)
		(fp_poly
			(pts
				(xy -3.359912 -0.849884) (xy -3.359912 6.390132) (xy -1.7653 6.390132) (xy -1.7653 6.503924) (xy 1.7653 6.503924)
				(xy 1.7653 6.390132) (xy 3.359912 6.390132) (xy 3.359912 -0.849884) (xy 1.7653 -0.849884) (xy 1.7653 -0.963676)
				(xy -1.7653 -0.963676) (xy -1.7653 -0.849884)
			)
			(stroke
				(width 0)
				(type default)
			)
			(fill no)
			(layer "F.CrtYd")
		)
		(fp_line
			(start 3.359912 6.390132)
			(end -3.359912 6.390132)
			(stroke
				(width 0.1)
				(type default)
			)
			(layer "F.Fab")
		)
		(fp_line
			(start 3.359912 -0.849884)
			(end 3.359912 6.390132)
			(stroke
				(width 0.1)
				(type default)
			)
			(layer "F.Fab")
		)
		(fp_line
			(start -3.359912 6.390132)
			(end -3.359912 -0.849884)
			(stroke
				(width 0.1)
				(type default)
			)
			(layer "F.Fab")
		)
		(fp_line
			(start -3.359912 -0.849884)
			(end 3.359912 -0.849884)
			(stroke
				(width 0.1)
				(type default)
			)
			(layer "F.Fab")
		)
		(pad "1A" smd rect
			(at 0 0 90)
			(size 1.8288 3.429)
			(layers "F.Cu" "F.Mask" "F.Paste")
			(net "PV_VCCP_NODE1")
		)
		(pad "1B" smd rect
			(at 0 0.787908 90)
			(size 0.254 0.508)
			(layers "F.Cu" "F.Mask" "F.Paste")
			(net "ISENSE_PVCCP_NODE1_ISEN1N")
		)
		(pad "2A" smd rect
			(at 0 5.539994 90)
			(size 1.8288 3.429)
			(layers "F.Cu" "F.Mask" "F.Paste")
			(net "VR_PVCCP_NODE1_PHASE1")
		)
		(pad "2B" smd rect
			(at 0 4.753102 90)
			(size 0.254 0.508)
			(layers "F.Cu" "F.Mask" "F.Paste")
			(net "ISENSE_PVCCP_NODE1_ISEN1P")
		)
	)
)
